#ISCELL
  mstr_misc dns *
  *
#ISCELL
  mstr_symbols intel_corp_bpage *
  *
#ISCELL
  mstr_symbols gnd *
  page151_i1
#CELL
  mstr_discrete res *
  page151_i10
#CELL
  mstr_discrete res *
  page151_i11
#CELL
  mstr_discrete res *
  page151_i12
#CELL
  mstr_discrete res *
  page151_i13
#CELL
  mstr_discrete res *
  page151_i14
#ISCELL
  mstr_symbols p3v3_stby *
  page151_i15
#ISCELL
  mstr_standard offpage *
  page151_i16
#ISCELL
  mstr_standard offpage *
  page151_i17
#ISCELL
  mstr_standard offpage *
  page151_i18
#ISCELL
  mstr_standard offpage *
  page151_i19
#CELL
  mstr_discrete res *
  page151_i2
#ISCELL
  mstr_standard offpage *
  page151_i20
#ISCELL
  mstr_standard offpage *
  page151_i21
#ISCELL
  mstr_standard offpage *
  page151_i22
#ISCELL
  mstr_standard offpage *
  page151_i23
#ISCELL
  mstr_standard offpage *
  page151_i24
#ISCELL
  mstr_standard offpage *
  page151_i25
#ISCELL
  mstr_standard offpage *
  page151_i26
#CELL
  mstr_discrete res *
  page151_i27
#CELL
  mstr_discrete res *
  page151_i28
#CELL
  mstr_discrete res *
  page151_i29
#ISCELL
  mstr_standard offpage *
  page151_i3
#CELL
  mstr_discrete res *
  page151_i30
#CELL
  mstr_discrete res *
  page151_i31
#CELL
  mstr_discrete res *
  page151_i32
#CELL
  mstr_discrete res *
  page151_i33
#CELL
  mstr_discrete res *
  page151_i34
#CELL
  mstr_discrete res *
  page151_i35
#CELL
  mstr_discrete res *
  page151_i36
#ISCELL
  mstr_standard offpage *
  page151_i37
#ISCELL
  mstr_standard offpage *
  page151_i38
#ISCELL
  mstr_standard offpage *
  page151_i39
#ISCELL
  mstr_standard offpage *
  page151_i4
#ISCELL
  mstr_standard offpage *
  page151_i40
#ISCELL
  mstr_standard offpage *
  page151_i41
#ISCELL
  mstr_standard offpage *
  page151_i42
#CELL
  mstr_discrete res *
  page151_i43
#CELL
  mstr_discrete res *
  page151_i44
#CELL
  mstr_discrete res *
  page151_i45
#CELL
  mstr_discrete res *
  page151_i46
#CELL
  mstr_discrete res *
  page151_i47
#CELL
  mstr_discrete res *
  page151_i48
#ISCELL
  mstr_standard offpage *
  page151_i5
#ISCELL
  mstr_standard offpage *
  page151_i6
#ISCELL
  mstr_standard offpage *
  page151_i7
#ISCELL
  mstr_standard offpage *
  page151_i8
#CELL
  mstr_discrete res *
  page151_i9
